(kicad_pcb
	(version 20260206)
	(generator "pcbnew")
	(generator_version "10.0")
	(general
		(thickness 1.6)
		(legacy_teardrops no)
	)
	(paper "A4")
	(title_block
		(title "Bryce Canyon_F.DPB_16315-1-OCP.brd")
		(comment 1 "Bryce Canyon / footprints 52-54 of 2223")
	)
	(layers
		(0 "F.Cu" signal "TOP")
		(4 "In1.Cu" signal "L2GND")
		(6 "In2.Cu" signal "L3")
		(8 "In3.Cu" signal "L4GND")
		(10 "In4.Cu" signal "L5")
		(12 "In5.Cu" signal "L6VCC")
		(14 "In6.Cu" signal "L7VCC")
		(16 "In7.Cu" signal "L8")
		(18 "In8.Cu" signal "L9GND")
		(20 "In9.Cu" signal "L10")
		(22 "In10.Cu" signal "L11GND")
		(2 "B.Cu" signal "BOTTOM")
		(9 "F.Adhes" user "F.Adhesive")
		(11 "B.Adhes" user "B.Adhesive")
		(13 "F.Paste" user "Package Geometry/Pastemask Top")
		(15 "B.Paste" user "Package Geometry/Pastemask Bottom")
		(5 "F.SilkS" user "Ref Des/Silkscreen Top")
		(7 "B.SilkS" user "Ref Des/Silkscreen Bottom")
		(1 "F.Mask" user "Board Geometry/Soldermask Top")
		(3 "B.Mask" user "Board Geometry/Soldermask Bottom")
		(17 "Dwgs.User" user "User.Drawings")
		(19 "Cmts.User" user "User.Comments")
		(21 "Eco1.User" user "User.Eco1")
		(23 "Eco2.User" user "User.Eco2")
		(25 "Edge.Cuts" user "Board Geometry/Outline")
		(27 "Margin" user)
		(31 "F.CrtYd" user "Package Geometry/Place Bound Top")
		(29 "B.CrtYd" user "Package Geometry/Place Bound Bottom")
		(35 "F.Fab" user "Ref Des/Assembly Top")
		(33 "B.Fab" user "Ref Des/Assembly Bottom")
	)
	(footprint ""
		(layer "F.Cu")
		(at 483.300024 -287.910016 -90)
		(property "Reference" "HDDSAS11"
			(at 0 0 270)
			(layer "F.SilkS")
			(hide yes)
			(effects
				(font
					(size 1.27 1.27)
				)
			)
		)
		(property "Value" "SKT-SAS15P-14P-45-GP"
			(at -20.7645 -8.9789 270)
			(unlocked yes)
			(layer "F.Fab")
			(hide yes)
			(effects
				(font
					(size 1.016 1.016)
					(thickness 0.1524)
				)
			)
		)
		(property "Device Type" "10120818-001C-TRLF"
			(at -20.7645 -10.5029 270)
			(unlocked yes)
			(layer "F.Fab")
			(hide yes)
			(effects
				(font
					(size 1.016 1.016)
					(thickness 0.1524)
				)
			)
		)
		(duplicate_pad_numbers_are_jumpers no)
		(fp_line
			(start 1.651 4.2926)
			(end 1.651 3.0099)
			(stroke
				(width 0.1524)
				(type default)
			)
			(layer "F.SilkS")
		)
		(fp_line
			(start 8.509 4.2926)
			(end 1.651 4.2926)
			(stroke
				(width 0.1524)
				(type default)
			)
			(layer "F.SilkS")
		)
		(fp_line
			(start -23.4188 3.0099)
			(end -23.4188 -3.2512)
			(stroke
				(width 0.1524)
				(type default)
			)
			(layer "F.SilkS")
		)
		(fp_line
			(start 1.651 3.0099)
			(end -23.4188 3.0099)
			(stroke
				(width 0.1524)
				(type default)
			)
			(layer "F.SilkS")
		)
		(fp_line
			(start 8.509 3.0099)
			(end 8.509 4.2926)
			(stroke
				(width 0.1524)
				(type default)
			)
			(layer "F.SilkS")
		)
		(fp_line
			(start 23.4188 3.0099)
			(end 8.509 3.0099)
			(stroke
				(width 0.1524)
				(type default)
			)
			(layer "F.SilkS")
		)
		(fp_line
			(start -23.4188 -3.2512)
			(end 23.4188 -3.2512)
			(stroke
				(width 0.1524)
				(type default)
			)
			(layer "F.SilkS")
		)
		(fp_line
			(start 23.4188 -3.2512)
			(end 23.4188 3.0099)
			(stroke
				(width 0.1524)
				(type default)
			)
			(layer "F.SilkS")
		)
		(fp_line
			(start 15.5067 -3.3401)
			(end 16.2687 -3.3401)
			(stroke
				(width 0.3302)
				(type default)
			)
			(layer "F.SilkS")
		)
		(fp_poly
			(pts
				(xy 15.868904 -3.230372) (xy 16.503904 -3.865372) (xy 15.233904 -3.865372)
			)
			(stroke
				(width 0)
				(type default)
			)
			(fill yes)
			(layer "F.SilkS")
		)
		(fp_poly
			(pts
				(xy -22.8727 -2.7559) (xy 22.8727 -2.7559) (xy 22.8727 2.7559) (xy 8.255 2.7559) (xy 8.255 3.5179)
				(xy 1.905 3.5179) (xy 1.905 2.7559) (xy -22.8727 2.7559)
			)
			(stroke
				(width 0)
				(type default)
			)
			(fill no)
			(layer "F.CrtYd")
		)
		(fp_poly
			(pts
				(xy 1.397 4.5466) (xy 1.397 3.2639) (xy -23.6728 3.2639) (xy -23.6728 -3.5052) (xy 23.6728 -3.5052)
				(xy 23.6728 -0.00635) (xy 22.8727 -0.00635) (xy 22.8727 -2.7559) (xy -22.8727 -2.7559) (xy -22.8727 2.7559)
				(xy 1.905 2.7559) (xy 1.905 3.5179) (xy 8.255 3.5179) (xy 8.255 2.7559) (xy 22.8727 2.7559) (xy 22.8727 0.00635)
				(xy 23.6728 0.00635) (xy 23.6728 3.2639) (xy 8.763 3.2639) (xy 8.763 4.5466)
			)
			(stroke
				(width 0)
				(type default)
			)
			(fill no)
			(layer "F.CrtYd")
		)
		(fp_poly
			(pts
				(xy 1.397 4.5466) (xy 1.397 3.2639) (xy -23.6728 3.2639) (xy -23.6728 -3.5052) (xy 23.6728 -3.5052)
				(xy 23.6728 3.2639) (xy 8.763 3.2639) (xy 8.763 4.5466)
			)
			(stroke
				(width 0)
				(type default)
			)
			(fill no)
			(layer "F.Fab")
		)
		(pad "" np_thru_hole circle
			(at -18.874994 0 270)
			(size 0.254 0.254)
			(drill 1.3462)
			(layers "*.Cu" "*.Mask")
			(clearance 0.9017)
			(thermal_gap 0.9017)
		)
		(pad "" np_thru_hole circle
			(at 18.874994 0 270)
			(size 0.254 0.254)
			(drill 0.9398)
			(layers "*.Cu" "*.Mask")
			(clearance 0.6985)
			(thermal_gap 0.6985)
		)
		(pad "G1" smd rect
			(at 21.874988 0 270)
			(size 2.5908 2.5908)
			(layers "F.Cu" "F.Mask" "F.Paste")
			(net "GND")
		)
		(pad "G2" smd rect
			(at -21.874988 0 270)
			(size 2.5908 2.5908)
			(layers "F.Cu" "F.Mask" "F.Paste")
			(net "GND")
		)
		(pad "P1" smd rect
			(at 1.905 -1.82499 270)
			(size 0.6096 2.3622)
			(layers "F.Cu" "F.Mask" "F.Paste")
			(net "Net_2161")
		)
		(pad "P2" smd rect
			(at 0.635 -1.82499 270)
			(size 0.6096 2.3622)
			(layers "F.Cu" "F.Mask" "F.Paste")
			(net "Net_2162")
		)
		(pad "P3" smd rect
			(at -0.635 -1.82499 270)
			(size 0.6096 2.3622)
			(layers "F.Cu" "F.Mask" "F.Paste")
			(net "Net_2163")
		)
		(pad "P4" smd rect
			(at -1.905 -1.82499 270)
			(size 0.6096 2.3622)
			(layers "F.Cu" "F.Mask" "F.Paste")
			(net "GND")
		)
		(pad "P5" smd rect
			(at -3.175 -1.82499 270)
			(size 0.6096 2.3622)
			(layers "F.Cu" "F.Mask" "F.Paste")
			(net "HDD_PRSNT_11")
		)
		(pad "P6" smd rect
			(at -4.445 -1.82499 270)
			(size 0.6096 2.3622)
			(layers "F.Cu" "F.Mask" "F.Paste")
			(net "GND")
		)
		(pad "P7" smd rect
			(at -5.715 -1.82499 270)
			(size 0.6096 2.3622)
			(layers "F.Cu" "F.Mask" "F.Paste")
			(net "5V_PRE_11")
		)
		(pad "P8" smd rect
			(at -6.985 -1.82499 270)
			(size 0.6096 2.3622)
			(layers "F.Cu" "F.Mask" "F.Paste")
			(net "P5V_HDD11")
		)
		(pad "P9" smd rect
			(at -8.255 -1.82499 270)
			(size 0.6096 2.3622)
			(layers "F.Cu" "F.Mask" "F.Paste")
			(net "P5V_HDD11")
		)
		(pad "P10" smd rect
			(at -9.525 -1.82499 270)
			(size 0.6096 2.3622)
			(layers "F.Cu" "F.Mask" "F.Paste")
			(net "GND")
		)
		(pad "P11" smd rect
			(at -10.795 -1.82499 270)
			(size 0.6096 2.3622)
			(layers "F.Cu" "F.Mask" "F.Paste")
			(net "ACT_HDD_11")
		)
		(pad "P12" smd rect
			(at -12.065 -1.82499 270)
			(size 0.6096 2.3622)
			(layers "F.Cu" "F.Mask" "F.Paste")
			(net "GND")
		)
		(pad "P13" smd rect
			(at -13.335 -1.82499 270)
			(size 0.6096 2.3622)
			(layers "F.Cu" "F.Mask" "F.Paste")
			(net "12V_PRE_11")
		)
		(pad "P14" smd rect
			(at -14.605 -1.82499 270)
			(size 0.6096 2.3622)
			(layers "F.Cu" "F.Mask" "F.Paste")
			(net "P12V_HDD11")
		)
		(pad "P15" smd rect
			(at -15.875 -1.82499 270)
			(size 0.6096 2.3622)
			(layers "F.Cu" "F.Mask" "F.Paste")
			(net "P12V_HDD11")
		)
		(pad "S1" smd rect
			(at 15.875 -1.82499 270)
			(size 0.6096 2.3622)
			(layers "F.Cu" "F.Mask" "F.Paste")
			(net "GND")
		)
		(pad "S2" smd rect
			(at 14.605 -1.82499 270)
			(size 0.6096 2.3622)
			(layers "F.Cu" "F.Mask" "F.Paste")
			(net "SAS_HDD_RX_P11")
		)
		(pad "S3" smd rect
			(at 13.335 -1.82499 270)
			(size 0.6096 2.3622)
			(layers "F.Cu" "F.Mask" "F.Paste")
			(net "SAS_HDD_RX_N11")
		)
		(pad "S4" smd rect
			(at 12.065 -1.82499 270)
			(size 0.6096 2.3622)
			(layers "F.Cu" "F.Mask" "F.Paste")
			(net "GND")
		)
		(pad "S5" smd rect
			(at 10.795 -1.82499 270)
			(size 0.6096 2.3622)
			(layers "F.Cu" "F.Mask" "F.Paste")
			(net "PHY_DRV_A_TO_SCC_A_11_DN")
		)
		(pad "S6" smd rect
			(at 9.525 -1.82499 270)
			(size 0.6096 2.3622)
			(layers "F.Cu" "F.Mask" "F.Paste")
			(net "PHY_DRV_A_TO_SCC_A_11_DP")
		)
		(pad "S7" smd rect
			(at 8.255 -1.82499 270)
			(size 0.6096 2.3622)
			(layers "F.Cu" "F.Mask" "F.Paste")
			(net "GND")
		)
		(pad "S8" smd rect
			(at 7.480046 2.845054 270)
			(size 0.508 2.3622)
			(layers "F.Cu" "F.Mask" "F.Paste")
			(net "GND")
		)
		(pad "S9" smd rect
			(at 6.679946 2.845054 270)
			(size 0.508 2.3622)
			(layers "F.Cu" "F.Mask" "F.Paste")
			(net "Net_448")
		)
		(pad "S10" smd rect
			(at 5.8801 2.845054 270)
			(size 0.508 2.3622)
			(layers "F.Cu" "F.Mask" "F.Paste")
			(net "Net_340")
		)
		(pad "S11" smd rect
			(at 5.08 2.845054 270)
			(size 0.508 2.3622)
			(layers "F.Cu" "F.Mask" "F.Paste")
			(net "GND")
		)
		(pad "S12" smd rect
			(at 4.2799 2.845054 270)
			(size 0.508 2.3622)
			(layers "F.Cu" "F.Mask" "F.Paste")
			(net "Net_376")
		)
		(pad "S13" smd rect
			(at 3.480054 2.845054 270)
			(size 0.508 2.3622)
			(layers "F.Cu" "F.Mask" "F.Paste")
			(net "Net_412")
		)
		(pad "S14" smd rect
			(at 2.679954 2.845054 270)
			(size 0.508 2.3622)
			(layers "F.Cu" "F.Mask" "F.Paste")
			(net "GND")
		)
		(zone
			(layer "F.Cu")
			(hatch none 0.5)
			(connect_pads
				(clearance 0)
			)
			(min_thickness 0.25)
			(keepout
				(tracks allowed)
				(vias not_allowed)
				(pads allowed)
				(copperpour not_allowed)
				(footprints allowed)
			)
			(placement
				(enabled no)
				(sheetname "")
			)
			(fill
				(thermal_gap 0.5)
				(thermal_bridge_width 0.5)
				(island_removal_mode 0)
			)
			(polygon
				(pts
					(xy 486.957624 -304.648616) (xy 479.883724 -304.648616) (xy 479.883724 -311.582816) (xy 480.988624 -311.582816)
					(xy 480.988624 -307.468016) (xy 485.611424 -307.468016) (xy 485.611424 -311.582816) (xy 486.957624 -311.582816)
				)
			)
		)
		(zone
			(layer "F.Cu")
			(hatch none 0.5)
			(connect_pads
				(clearance 0)
			)
			(min_thickness 0.25)
			(keepout
				(tracks not_allowed)
				(vias allowed)
				(pads allowed)
				(copperpour not_allowed)
				(footprints allowed)
			)
			(placement
				(enabled no)
				(sheetname "")
			)
			(fill
				(thermal_gap 0.5)
				(thermal_bridge_width 0.5)
				(island_removal_mode 0)
			)
			(polygon
				(pts
					(xy 486.957624 -304.648616) (xy 479.883724 -304.648616) (xy 479.883724 -311.582816) (xy 480.988624 -311.582816)
					(xy 480.988624 -307.468016) (xy 485.611424 -307.468016) (xy 485.611424 -311.582816) (xy 486.957624 -311.582816)
				)
			)
		)
		(zone
			(layer "F.Cu")
			(hatch none 0.5)
			(connect_pads
				(clearance 0)
			)
			(min_thickness 0.25)
			(keepout
				(tracks allowed)
				(vias not_allowed)
				(pads allowed)
				(copperpour not_allowed)
				(footprints allowed)
			)
			(placement
				(enabled no)
				(sheetname "")
			)
			(fill
				(thermal_gap 0.5)
				(thermal_bridge_width 0.5)
				(island_removal_mode 0)
			)
			(polygon
				(pts
					(xy 486.957624 -271.171416) (xy 479.883724 -271.171416) (xy 479.883724 -264.237216) (xy 480.988624 -264.237216)
					(xy 480.988624 -268.352016) (xy 485.611424 -268.352016) (xy 485.611424 -264.237216) (xy 486.957624 -264.237216)
				)
			)
		)
		(zone
			(layer "F.Cu")
			(hatch none 0.5)
			(connect_pads
				(clearance 0)
			)
			(min_thickness 0.25)
			(keepout
				(tracks not_allowed)
				(vias allowed)
				(pads allowed)
				(copperpour not_allowed)
				(footprints allowed)
			)
			(placement
				(enabled no)
				(sheetname "")
			)
			(fill
				(thermal_gap 0.5)
				(thermal_bridge_width 0.5)
				(island_removal_mode 0)
			)
			(polygon
				(pts
					(xy 486.957624 -271.171416) (xy 479.883724 -271.171416) (xy 479.883724 -264.237216) (xy 480.988624 -264.237216)
					(xy 480.988624 -268.352016) (xy 485.611424 -268.352016) (xy 485.611424 -264.237216) (xy 486.957624 -264.237216)
				)
			)
		)
		(zone
			(layers "F.Cu" "B.Cu" "In1.Cu" "In2.Cu" "In3.Cu" "In4.Cu" "In5.Cu" "In6.Cu"
				"In7.Cu" "In8.Cu" "In9.Cu" "In10.Cu"
			)
			(hatch none 0.5)
			(connect_pads
				(clearance 0)
			)
			(min_thickness 0.25)
			(keepout
				(tracks not_allowed)
				(vias allowed)
				(pads allowed)
				(copperpour not_allowed)
				(footprints allowed)
			)
			(placement
				(enabled no)
				(sheetname "")
			)
			(fill
				(thermal_gap 0.5)
				(thermal_bridge_width 0.5)
				(island_removal_mode 0)
			)
			(polygon
				(pts
					(arc
						(start 484.074724 -269.035022)
						(mid 482.525324 -269.035022)
						(end 484.074724 -269.035022)
					)
				)
			)
		)
		(zone
			(layers "F.Cu" "B.Cu" "In1.Cu" "In2.Cu" "In3.Cu" "In4.Cu" "In5.Cu" "In6.Cu"
				"In7.Cu" "In8.Cu" "In9.Cu" "In10.Cu"
			)
			(hatch none 0.5)
			(connect_pads
				(clearance 0)
			)
			(min_thickness 0.25)
			(keepout
				(tracks not_allowed)
				(vias allowed)
				(pads allowed)
				(copperpour not_allowed)
				(footprints allowed)
			)
			(placement
				(enabled no)
				(sheetname "")
			)
			(fill
				(thermal_gap 0.5)
				(thermal_bridge_width 0.5)
				(island_removal_mode 0)
			)
			(polygon
				(pts
					(arc
						(start 484.277924 -306.78501)
						(mid 482.322124 -306.78501)
						(end 484.277924 -306.78501)
					)
				)
			)
		)
	)
	(footprint ""
		(layer "F.Cu")
		(at 300.20006 -393.205716)
		(property "Reference" ""
			(at 0 0 0)
			(layer "F.SilkS")
			(hide yes)
			(effects
				(font
					(size 1.27 1.27)
				)
			)
		)
		(property "Value" "*"
			(at -8.398764 -8.057642 0)
			(unlocked yes)
			(layer "F.Fab")
			(hide yes)
			(effects
				(font
					(size 1.016 1.016)
					(thickness 0.1524)
				)
			)
		)
		(duplicate_pad_numbers_are_jumpers no)
		(fp_poly
			(pts
				(arc
					(start 7.3152 0)
					(mid 0 7.3152)
					(end -7.3152 0)
				)
				(arc
					(start -7.3152 -5.9944)
					(mid 0 -13.3096)
					(end 7.3152 -5.9944)
				)
			)
			(stroke
				(width 0)
				(type default)
			)
			(fill no)
			(layer "B.CrtYd")
		)
		(fp_poly
			(pts
				(arc
					(start 7.3152 0)
					(mid 0 7.3152)
					(end -7.3152 0)
				)
				(arc
					(start -7.3152 -5.9944)
					(mid 0 -13.3096)
					(end 7.3152 -5.9944)
				)
			)
			(stroke
				(width 0)
				(type default)
			)
			(fill no)
			(layer "F.CrtYd")
		)
		(fp_poly
			(pts
				(arc
					(start 7.3152 0)
					(mid 0 7.3152)
					(end -7.3152 0)
				)
				(arc
					(start -7.3152 -5.9944)
					(mid 0 -13.3096)
					(end 7.3152 -5.9944)
				)
			)
			(stroke
				(width 0)
				(type default)
			)
			(fill no)
			(layer "B.Fab")
		)
		(fp_poly
			(pts
				(arc
					(start 7.3152 0)
					(mid 0 7.3152)
					(end -7.3152 0)
				)
				(arc
					(start -7.3152 -5.9944)
					(mid 0 -13.3096)
					(end 7.3152 -5.9944)
				)
			)
			(stroke
				(width 0)
				(type default)
			)
			(fill no)
			(layer "F.Fab")
		)
		(pad "1" thru_hole oval
			(at 0 0)
			(size 14.0208 20.0152)
			(drill 0.0254
				(offset 0 -2.9972)
			)
			(layers "*.Cu" "*.Mask")
			(remove_unused_layers no)
			(net "Net_65")
			(clearance -1.002284)
			(thermal_gap 0.1524)
			(padstack
				(mode front_inner_back)
				(layer "Inner"
					(shape custom)
					(size 2.928012 2.928012)
					(options
						(anchor circle)
					)
					(primitives
						(gr_poly
							(pts
								(arc
									(start 4.571746 -2.084324)
									(mid 0.000333 7.430372)
									(end -4.571492 -2.084324)
								)
								(arc
									(start -4.571492 -2.084324)
									(mid -3.570296 -3.611977)
									(end -2.875026 -5.30098)
								)
								(arc
									(start -2.875026 -5.30098)
									(mid 0.000217 -7.43089)
									(end 2.87528 -5.30098)
								)
								(arc
									(start 2.87528 -5.30098)
									(mid 3.570511 -3.611956)
									(end 4.571746 -2.084324)
								)
							)
							(width 0)
							(fill yes)
						)
					)
					(clearance 0.1524)
				)
				(layer "B.Cu"
					(shape oval)
					(size 14.0208 20.0152)
					(offset 0 -2.9972)
					(clearance -1.002284)
				)
			)
		)
		(zone
			(layers "F.Cu" "B.Cu" "In1.Cu" "In2.Cu" "In3.Cu" "In4.Cu" "In5.Cu" "In6.Cu"
				"In7.Cu" "In8.Cu" "In9.Cu" "In10.Cu"
			)
			(hatch none 0.5)
			(connect_pads
				(clearance 0)
			)
			(min_thickness 0.25)
			(keepout
				(tracks not_allowed)
				(vias allowed)
				(pads allowed)
				(copperpour not_allowed)
				(footprints allowed)
			)
			(placement
				(enabled no)
				(sheetname "")
			)
			(fill
				(thermal_gap 0.5)
				(thermal_bridge_width 0.5)
				(island_removal_mode 0)
			)
			(polygon
				(pts
					(arc
						(start 293.18966 -399.200116)
						(mid 300.20006 -406.210516)
						(end 307.21046 -399.200116)
					)
					(arc
						(start 307.21046 -393.205716)
						(mid 300.20006 -386.195316)
						(end 293.18966 -393.205716)
					)
				)
			)
		)
	)
	(footprint ""
		(layer "F.Cu")
		(at 321.279012 -127.360934)
		(property "Reference" "R315"
			(at 0 0 0)
			(layer "F.SilkS")
			(hide yes)
			(effects
				(font
					(size 1.27 1.27)
				)
			)
		)
		(property "Value" "130R3F-GP"
			(at -0.0254 -2.5146 0)
			(unlocked yes)
			(layer "F.Fab")
			(hide yes)
			(effects
				(font
					(size 1.016 1.016)
					(thickness 0.1524)
				)
			)
		)
		(property "Device Type" "R603H22"
			(at -0.0254 -4.0386 0)
			(unlocked yes)
			(layer "F.Fab")
			(hide yes)
			(effects
				(font
					(size 1.016 1.016)
					(thickness 0.1524)
				)
			)
		)
		(duplicate_pad_numbers_are_jumpers no)
		(fp_line
			(start -0.4826 0)
			(end -0.2032 0)
			(stroke
				(width 0.2032)
				(type default)
			)
			(layer "F.SilkS")
		)
		(fp_line
			(start 0.2032 0)
			(end 0.4826 0)
			(stroke
				(width 0.2032)
				(type default)
			)
			(layer "F.SilkS")
		)
		(fp_rect
			(start -0.5842 1.3335)
			(end 0.5842 -1.3335)
			(stroke
				(width 0)
				(type default)
			)
			(fill no)
			(layer "F.CrtYd")
		)
		(fp_rect
			(start -0.5842 1.3335)
			(end 0.5842 -1.3335)
			(stroke
				(width 0)
				(type default)
			)
			(fill no)
			(layer "F.Fab")
		)
		(pad "1" smd custom
			(at 0 -0.762)
			(size 0.2159 0.2159)
			(layers "F.Cu" "F.Mask" "F.Paste")
			(net "P5V_A_3")
			(options
				(clearance outline)
				(anchor circle)
			)
			(primitives
				(gr_poly
					(pts
						(arc
							(start -0.3302 -0.4318)
							(mid -0.402042 -0.402042)
							(end -0.4318 -0.3302)
						)
						(arc
							(start -0.4318 0.3302)
							(mid -0.402042 0.402042)
							(end -0.3302 0.4318)
						)
						(arc
							(start 0.3302 0.4318)
							(mid 0.402042 0.402042)
							(end 0.4318 0.3302)
						)
						(arc
							(start 0.4318 -0.3302)
							(mid 0.402042 -0.402042)
							(end 0.3302 -0.4318)
						)
					)
					(width 0)
					(fill yes)
				)
			)
		)
		(pad "2" smd custom
			(at 0 0.762)
			(size 0.2159 0.2159)
			(layers "F.Cu" "F.Mask" "F.Paste")
			(net "FLT_HDD18")
			(options
				(clearance outline)
				(anchor circle)
			)
			(primitives
				(gr_poly
					(pts
						(arc
							(start -0.3302 -0.4318)
							(mid -0.402042 -0.402042)
							(end -0.4318 -0.3302)
						)
						(arc
							(start -0.4318 0.3302)
							(mid -0.402042 0.402042)
							(end -0.3302 0.4318)
						)
						(arc
							(start 0.3302 0.4318)
							(mid 0.402042 0.402042)
							(end 0.4318 0.3302)
						)
						(arc
							(start 0.4318 -0.3302)
							(mid 0.402042 -0.402042)
							(end 0.3302 -0.4318)
						)
					)
					(width 0)
					(fill yes)
				)
			)
		)
	)
)
